(kicad_pcb
	(version 20260206)
	(generator "pcbnew")
	(generator_version "10.0")
	(general
		(thickness 1.6)
		(legacy_teardrops no)
	)
	(paper "A4")
	(title_block
		(title "v1-chassis-manager — T6M_CM_d_v01_1031_1645.brd")
		(comment 1 "Open CloudServer (Microsoft) / footprints 798-804 of 2512")
	)
	(layers
		(0 "F.Cu" signal "TOP")
		(4 "In1.Cu" signal "GND1")
		(6 "In2.Cu" signal "IN1")
		(8 "In3.Cu" signal "VCC1")
		(10 "In4.Cu" signal "VCC2")
		(12 "In5.Cu" signal "GND2")
		(14 "In6.Cu" signal "IN2")
		(16 "In7.Cu" signal "IN3")
		(18 "In8.Cu" signal "GND3")
		(2 "B.Cu" signal "BOTTOM")
		(9 "F.Adhes" user "F.Adhesive")
		(11 "B.Adhes" user "B.Adhesive")
		(13 "F.Paste" user "Package Geometry/Pastemask Top")
		(15 "B.Paste" user "Package Geometry/Pastemask Bottom")
		(5 "F.SilkS" user "Ref Des/Silkscreen Top")
		(7 "B.SilkS" user "Ref Des/Silkscreen Bottom")
		(1 "F.Mask" user "Board Geometry/Soldermask Top")
		(3 "B.Mask" user "Board Geometry/Soldermask Bottom")
		(17 "Dwgs.User" user "User.Drawings")
		(19 "Cmts.User" user "User.Comments")
		(21 "Eco1.User" user "User.Eco1")
		(23 "Eco2.User" user "User.Eco2")
		(25 "Edge.Cuts" user "Board Geometry/Outline")
		(27 "Margin" user)
		(31 "F.CrtYd" user "Package Geometry/Place Bound Top")
		(29 "B.CrtYd" user "Package Geometry/Place Bound Bottom")
		(35 "F.Fab" user "Ref Des/Assembly Top")
		(33 "B.Fab" user "Ref Des/Assembly Bottom")
	)
	(footprint ""
		(layer "F.Cu")
		(at -6.825488 -59.063382 90)
		(property "Reference" "J4"
			(at 1.44272 -6.64083 90)
			(unlocked yes)
			(layer "F.SilkS")
			(effects
				(font
					(size 0.7874 0.5842)
					(thickness 0.1524)
				)
				(justify left)
			)
		)
		(property "Value" ""
			(at 0 0 90)
			(layer "F.Fab")
			(effects
				(font
					(size 1.27 1.27)
				)
			)
		)
		(duplicate_pad_numbers_are_jumpers no)
		(fp_circle
			(center 4.064 -4.572)
			(end 4.064 -3.937)
			(stroke
				(width 0.05)
				(type default)
			)
			(fill no)
			(layer "Edge.Cuts")
		)
		(fp_circle
			(center 0 -4.572)
			(end 0 -3.937)
			(stroke
				(width 0.05)
				(type default)
			)
			(fill no)
			(layer "Edge.Cuts")
		)
		(fp_circle
			(center 4.064 0)
			(end 4.064 0.635)
			(stroke
				(width 0.05)
				(type default)
			)
			(fill no)
			(layer "Edge.Cuts")
		)
		(fp_circle
			(center 0 0)
			(end 0 0.635)
			(stroke
				(width 0.05)
				(type default)
			)
			(fill no)
			(layer "Edge.Cuts")
		)
		(fp_rect
			(start -1.27 1.27)
			(end 5.334 -5.842)
			(stroke
				(width 0)
				(type default)
			)
			(fill no)
			(layer "F.CrtYd")
		)
		(pad "" np_thru_hole circle
			(at 0 -4.572 90)
			(size 0.254 0.254)
			(drill 1.27)
			(layers "*.Cu" "*.Mask")
			(clearance 0.889)
			(thermal_gap 0.889)
		)
		(pad "" np_thru_hole circle
			(at 0 0 90)
			(size 0.254 0.254)
			(drill 1.27)
			(layers "*.Cu" "*.Mask")
			(clearance 0.889)
			(thermal_gap 0.889)
		)
		(pad "" np_thru_hole circle
			(at 4.064 -4.572 90)
			(size 0.254 0.254)
			(drill 1.27)
			(layers "*.Cu" "*.Mask")
			(clearance 0.889)
			(thermal_gap 0.889)
		)
		(pad "" np_thru_hole circle
			(at 4.064 0 90)
			(size 0.254 0.254)
			(drill 1.27)
			(layers "*.Cu" "*.Mask")
			(clearance 0.889)
			(thermal_gap 0.889)
		)
		(pad "1" thru_hole custom
			(at 1.397 -2.286 180)
			(size 0.266741 0.266741)
			(drill 0.254)
			(layers "*.Cu" "*.Mask")
			(remove_unused_layers no)
			(net "GND")
			(options
				(clearance outline)
				(anchor circle)
			)
			(primitives
				(gr_poly
					(pts
						(xy -0.979932 0.5334)
						(arc
							(start -0.979932 -0.078994)
							(mid -0.925932 -0.48038)
							(end -0.527812 -0.4064)
						)
						(arc
							(start -0.234188 -0.4064)
							(mid 0 -0.53341)
							(end 0.234188 -0.4064)
						)
						(arc
							(start 0.527812 -0.4064)
							(mid 0.925878 -0.480305)
							(end 0.979932 -0.078994)
						)
						(xy 0.979932 0.5334) (xy 0.548132 0.5334) (xy 0.548132 0.1016) (xy -0.548132 0.1016) (xy -0.548132 0.5334)
					)
					(width 0)
					(fill yes)
				)
			)
			(padstack
				(mode front_inner_back)
				(layer "Inner"
					(shape custom)
					(size 0.139735 0.139735)
					(options
						(anchor circle)
					)
					(primitives
						(gr_poly
							(pts
								(arc
									(start 0.26035 0.1016)
									(mid 0 0.279472)
									(end -0.26035 0.1016)
								)
								(arc
									(start -0.50165 0.1016)
									(mid -1.041472 0)
									(end -0.50165 -0.1016)
								)
								(arc
									(start -0.26035 -0.1016)
									(mid 0 -0.279472)
									(end 0.26035 -0.1016)
								)
								(arc
									(start 0.50165 -0.1016)
									(mid 1.041472 0)
									(end 0.50165 0.1016)
								)
							)
							(width 0)
							(fill yes)
						)
					)
				)
				(layer "B.Cu"
					(shape custom)
					(size 0.139735 0.139735)
					(options
						(anchor circle)
					)
					(primitives
						(gr_poly
							(pts
								(arc
									(start 0.26035 0.1016)
									(mid 0 0.279472)
									(end -0.26035 0.1016)
								)
								(arc
									(start -0.50165 0.1016)
									(mid -1.041472 0)
									(end -0.50165 -0.1016)
								)
								(arc
									(start -0.26035 -0.1016)
									(mid 0 -0.279472)
									(end 0.26035 -0.1016)
								)
								(arc
									(start 0.50165 -0.1016)
									(mid 1.041472 0)
									(end 0.50165 0.1016)
								)
							)
							(width 0)
							(fill yes)
						)
					)
				)
			)
		)
		(pad "2" smd rect
			(at 2.032 -2.060956 90)
			(size 0.3048 0.2032)
			(layers "F.Cu" "F.Mask" "F.Paste")
			(net "TOP_85OHM")
		)
		(pad "3" smd rect
			(at 2.032 -2.511044 90)
			(size 0.3048 0.2032)
			(layers "F.Cu" "F.Mask" "F.Paste")
			(net "TOP_85OHM")
		)
		(zone
			(layers "F.Cu" "B.Cu" "In1.Cu" "In2.Cu" "In3.Cu" "In4.Cu" "In5.Cu" "In6.Cu"
				"In7.Cu" "In8.Cu"
			)
			(hatch none 0.5)
			(connect_pads
				(clearance 0)
			)
			(min_thickness 0.25)
			(keepout
				(tracks not_allowed)
				(vias allowed)
				(pads allowed)
				(copperpour not_allowed)
				(footprints allowed)
			)
			(placement
				(enabled no)
				(sheetname "")
			)
			(fill
				(thermal_gap 0.5)
				(thermal_bridge_width 0.5)
				(island_removal_mode 0)
			)
			(polygon
				(pts
					(arc
						(start -11.397488 -64.016382)
						(mid -11.397488 -62.238382)
						(end -11.397488 -64.016382)
					)
				)
			)
		)
		(zone
			(layers "F.Cu" "B.Cu" "In1.Cu" "In2.Cu" "In3.Cu" "In4.Cu" "In5.Cu" "In6.Cu"
				"In7.Cu" "In8.Cu"
			)
			(hatch none 0.5)
			(connect_pads
				(clearance 0)
			)
			(min_thickness 0.25)
			(keepout
				(tracks not_allowed)
				(vias allowed)
				(pads allowed)
				(copperpour not_allowed)
				(footprints allowed)
			)
			(placement
				(enabled no)
				(sheetname "")
			)
			(fill
				(thermal_gap 0.5)
				(thermal_bridge_width 0.5)
				(island_removal_mode 0)
			)
			(polygon
				(pts
					(arc
						(start -11.397488 -59.952382)
						(mid -11.397488 -58.174382)
						(end -11.397488 -59.952382)
					)
				)
			)
		)
		(zone
			(layers "F.Cu" "B.Cu" "In1.Cu" "In2.Cu" "In3.Cu" "In4.Cu" "In5.Cu" "In6.Cu"
				"In7.Cu" "In8.Cu"
			)
			(hatch none 0.5)
			(connect_pads
				(clearance 0)
			)
			(min_thickness 0.25)
			(keepout
				(tracks not_allowed)
				(vias allowed)
				(pads allowed)
				(copperpour not_allowed)
				(footprints allowed)
			)
			(placement
				(enabled no)
				(sheetname "")
			)
			(fill
				(thermal_gap 0.5)
				(thermal_bridge_width 0.5)
				(island_removal_mode 0)
			)
			(polygon
				(pts
					(arc
						(start -6.825488 -64.016382)
						(mid -6.825488 -62.238382)
						(end -6.825488 -64.016382)
					)
				)
			)
		)
		(zone
			(layers "F.Cu" "B.Cu" "In1.Cu" "In2.Cu" "In3.Cu" "In4.Cu" "In5.Cu" "In6.Cu"
				"In7.Cu" "In8.Cu"
			)
			(hatch none 0.5)
			(connect_pads
				(clearance 0)
			)
			(min_thickness 0.25)
			(keepout
				(tracks not_allowed)
				(vias allowed)
				(pads allowed)
				(copperpour not_allowed)
				(footprints allowed)
			)
			(placement
				(enabled no)
				(sheetname "")
			)
			(fill
				(thermal_gap 0.5)
				(thermal_bridge_width 0.5)
				(island_removal_mode 0)
			)
			(polygon
				(pts
					(arc
						(start -6.825488 -59.952382)
						(mid -6.825488 -58.174382)
						(end -6.825488 -59.952382)
					)
				)
			)
		)
	)
	(footprint ""
		(layer "F.Cu")
		(at 68.81876 -185.205624 -90)
		(property "Reference" "R871"
			(at -4.006088 0.814324 90)
			(unlocked yes)
			(layer "F.SilkS")
			(effects
				(font
					(size 0.7874 0.5842)
					(thickness 0.1524)
				)
				(justify left)
			)
		)
		(property "Value" ""
			(at 0 0 270)
			(layer "F.Fab")
			(effects
				(font
					(size 1.27 1.27)
				)
			)
		)
		(duplicate_pad_numbers_are_jumpers no)
		(fp_line
			(start -0.7874 0.4064)
			(end -0.7874 -0.4064)
			(stroke
				(width 0.1524)
				(type default)
			)
			(layer "F.SilkS")
		)
		(fp_line
			(start 0.7874 0.4064)
			(end -0.7874 0.4064)
			(stroke
				(width 0.1524)
				(type default)
			)
			(layer "F.SilkS")
		)
		(fp_line
			(start -0.7874 -0.4064)
			(end 0.7874 -0.4064)
			(stroke
				(width 0.1524)
				(type default)
			)
			(layer "F.SilkS")
		)
		(fp_line
			(start 0.7874 -0.4064)
			(end 0.7874 0.4064)
			(stroke
				(width 0.1524)
				(type default)
			)
			(layer "F.SilkS")
		)
		(fp_poly
			(pts
				(xy -0.508 0.2794) (xy -0.508 0.2286) (xy -0.635 0.2286) (xy -0.635 -0.254) (xy -0.5334 -0.254)
				(xy -0.5334 -0.2794) (xy 0.5334 -0.2794) (xy 0.5334 -0.254) (xy 0.635 -0.254) (xy 0.635 0.254) (xy 0.5334 0.254)
				(xy 0.5334 0.2794)
			)
			(stroke
				(width 0)
				(type default)
			)
			(fill no)
			(layer "F.CrtYd")
		)
		(pad "1" smd rect
			(at 0.40005 0 270)
			(size 0.4572 0.508)
			(layers "F.Cu" "F.Mask" "F.Paste")
			(net "T2_NODE1_EN")
		)
		(pad "2" smd rect
			(at -0.40005 0 270)
			(size 0.4572 0.508)
			(layers "F.Cu" "F.Mask" "F.Paste")
			(net "T2_NODE1_EN_R")
		)
	)
	(footprint ""
		(layer "F.Cu")
		(at 144.916652 -141.20495)
		(property "Reference" "R232"
			(at -0.990346 17.763744 0)
			(unlocked yes)
			(layer "F.SilkS")
			(effects
				(font
					(size 0.7874 0.5842)
					(thickness 0.1524)
				)
				(justify left)
			)
		)
		(property "Value" ""
			(at 0 0 0)
			(layer "F.Fab")
			(effects
				(font
					(size 1.27 1.27)
				)
			)
		)
		(duplicate_pad_numbers_are_jumpers no)
		(fp_line
			(start -0.7874 -0.4064)
			(end 0.7874 -0.4064)
			(stroke
				(width 0.1524)
				(type default)
			)
			(layer "F.SilkS")
		)
		(fp_line
			(start -0.7874 0.4064)
			(end -0.7874 -0.4064)
			(stroke
				(width 0.1524)
				(type default)
			)
			(layer "F.SilkS")
		)
		(fp_line
			(start 0.7874 -0.4064)
			(end 0.7874 0.4064)
			(stroke
				(width 0.1524)
				(type default)
			)
			(layer "F.SilkS")
		)
		(fp_line
			(start 0.7874 0.4064)
			(end -0.7874 0.4064)
			(stroke
				(width 0.1524)
				(type default)
			)
			(layer "F.SilkS")
		)
		(fp_poly
			(pts
				(xy -0.508 0.2794) (xy -0.508 0.2286) (xy -0.635 0.2286) (xy -0.635 -0.254) (xy -0.5334 -0.254)
				(xy -0.5334 -0.2794) (xy 0.5334 -0.2794) (xy 0.5334 -0.254) (xy 0.635 -0.254) (xy 0.635 0.254) (xy 0.5334 0.254)
				(xy 0.5334 0.2794)
			)
			(stroke
				(width 0)
				(type default)
			)
			(fill no)
			(layer "F.CrtYd")
		)
		(pad "1" smd rect
			(at 0.40005 0)
			(size 0.4572 0.508)
			(layers "F.Cu" "F.Mask" "F.Paste")
			(net "SMB_CPU_NODE1_BMC_CLK")
		)
		(pad "2" smd rect
			(at -0.40005 0)
			(size 0.4572 0.508)
			(layers "F.Cu" "F.Mask" "F.Paste")
			(net "PCIE_SW_I2C_SCL")
		)
	)
	(footprint ""
		(layer "F.Cu")
		(at 113.64976 -179.363624 -90)
		(property "Reference" "D24"
			(at -3.131312 -8.24611 90)
			(unlocked yes)
			(layer "F.SilkS")
			(effects
				(font
					(size 0.635 0.4064)
					(thickness 0.1524)
				)
				(justify left)
			)
		)
		(property "Value" ""
			(at 0 0 270)
			(layer "F.Fab")
			(effects
				(font
					(size 1.27 1.27)
				)
			)
		)
		(duplicate_pad_numbers_are_jumpers no)
		(fp_line
			(start -1.3208 0.5588)
			(end -1.3208 -0.5588)
			(stroke
				(width 0.1524)
				(type default)
			)
			(layer "F.SilkS")
		)
		(fp_line
			(start 1.3208 0.5588)
			(end -1.3208 0.5588)
			(stroke
				(width 0.1524)
				(type default)
			)
			(layer "F.SilkS")
		)
		(fp_line
			(start 1.6256 0.5588)
			(end 1.6256 -0.5588)
			(stroke
				(width 0.1524)
				(type default)
			)
			(layer "F.SilkS")
		)
		(fp_line
			(start 1.778 0.5588)
			(end 1.3208 0.5588)
			(stroke
				(width 0.1524)
				(type default)
			)
			(layer "F.SilkS")
		)
		(fp_line
			(start -1.3208 -0.5588)
			(end 1.3208 -0.5588)
			(stroke
				(width 0.1524)
				(type default)
			)
			(layer "F.SilkS")
		)
		(fp_line
			(start 1.3208 -0.5588)
			(end 1.3208 0.5588)
			(stroke
				(width 0.1524)
				(type default)
			)
			(layer "F.SilkS")
		)
		(fp_line
			(start 1.4732 -0.5588)
			(end 1.4732 0.5588)
			(stroke
				(width 0.1524)
				(type default)
			)
			(layer "F.SilkS")
		)
		(fp_line
			(start 1.778 -0.5588)
			(end 1.778 0.5588)
			(stroke
				(width 0.1524)
				(type default)
			)
			(layer "F.SilkS")
		)
		(fp_line
			(start 1.778 -0.5588)
			(end 1.3208 -0.5588)
			(stroke
				(width 0.1524)
				(type default)
			)
			(layer "F.SilkS")
		)
		(fp_rect
			(start -1.1684 0.508)
			(end 1.1684 -0.508)
			(stroke
				(width 0)
				(type default)
			)
			(fill no)
			(layer "F.CrtYd")
		)
		(pad "A" smd rect
			(at -0.750062 0 270)
			(size 0.8128 0.8128)
			(layers "F.Cu" "F.Mask" "F.Paste")
			(net "UART_SW_S5_N")
		)
		(pad "C" smd rect
			(at 0.750062 0 270)
			(size 0.8128 0.8128)
			(layers "F.Cu" "F.Mask" "F.Paste")
			(net "N31348569")
		)
	)
	(footprint ""
		(layer "F.Cu")
		(at 18.25752 -50.345086 -90)
		(property "Reference" "C500"
			(at 1.057148 -13.781532 90)
			(unlocked yes)
			(layer "F.SilkS")
			(effects
				(font
					(size 0.7874 0.5842)
					(thickness 0.1524)
				)
			)
		)
		(property "Value" ""
			(at 0 0 270)
			(layer "F.Fab")
			(effects
				(font
					(size 1.27 1.27)
				)
			)
		)
		(duplicate_pad_numbers_are_jumpers no)
		(fp_line
			(start -1.2954 0.5842)
			(end -1.2954 -0.5842)
			(stroke
				(width 0.1524)
				(type default)
			)
			(layer "F.SilkS")
		)
		(fp_line
			(start 1.2954 0.5842)
			(end -1.2954 0.5842)
			(stroke
				(width 0.1524)
				(type default)
			)
			(layer "F.SilkS")
		)
		(fp_line
			(start -1.2954 -0.5842)
			(end 1.2954 -0.5842)
			(stroke
				(width 0.1524)
				(type default)
			)
			(layer "F.SilkS")
		)
		(fp_line
			(start 0 -0.5842)
			(end 0 0.5842)
			(stroke
				(width 0.1524)
				(type default)
			)
			(layer "F.SilkS")
		)
		(fp_line
			(start 1.2954 -0.5842)
			(end 1.2954 0.5842)
			(stroke
				(width 0.1524)
				(type default)
			)
			(layer "F.SilkS")
		)
		(fp_poly
			(pts
				(xy 0.8636 -0.4572) (xy 0.8636 -0.3556) (xy 1.143 -0.3556) (xy 1.143 0.3556) (xy 0.8636 0.3556)
				(xy 0.8636 0.4572) (xy -0.8636 0.4572) (xy -0.8636 0.3556) (xy -1.143 0.3556) (xy -1.143 -0.3556)
				(xy -0.8636 -0.3556) (xy -0.8636 -0.4572)
			)
			(stroke
				(width 0)
				(type default)
			)
			(fill no)
			(layer "F.CrtYd")
		)
		(fp_line
			(start -0.884936 0.504952)
			(end -0.884936 -0.504952)
			(stroke
				(width 0.1)
				(type default)
			)
			(layer "F.Fab")
		)
		(fp_line
			(start 0.884936 0.504952)
			(end -0.884936 0.504952)
			(stroke
				(width 0.1)
				(type default)
			)
			(layer "F.Fab")
		)
		(fp_line
			(start -0.884936 -0.504952)
			(end 0.884936 -0.504952)
			(stroke
				(width 0.1)
				(type default)
			)
			(layer "F.Fab")
		)
		(fp_line
			(start 0.884936 -0.504952)
			(end 0.884936 0.504952)
			(stroke
				(width 0.1)
				(type default)
			)
			(layer "F.Fab")
		)
		(pad "1" smd rect
			(at 0.7366 0)
			(size 0.7112 0.8128)
			(layers "F.Cu" "F.Mask" "F.Paste")
			(net "BMC_NODE1_GFX_GREEN")
		)
		(pad "2" smd rect
			(at -0.7366 0)
			(size 0.7112 0.8128)
			(layers "F.Cu" "F.Mask" "F.Paste")
			(net "GND")
		)
	)
	(footprint ""
		(layer "F.Cu")
		(at 102.888034 -181.31409 180)
		(property "Reference" "C776"
			(at -85.014308 -77.836776 90)
			(unlocked yes)
			(layer "F.SilkS")
			(effects
				(font
					(size 0.7874 0.5842)
					(thickness 0.1524)
				)
				(justify left)
			)
		)
		(property "Value" ""
			(at 0 0 180)
			(layer "F.Fab")
			(effects
				(font
					(size 1.27 1.27)
				)
			)
		)
		(duplicate_pad_numbers_are_jumpers no)
		(fp_line
			(start 0.7874 0.4064)
			(end -0.7874 0.4064)
			(stroke
				(width 0.1524)
				(type default)
			)
			(layer "F.SilkS")
		)
		(fp_line
			(start 0.7874 -0.4064)
			(end 0.7874 0.4064)
			(stroke
				(width 0.1524)
				(type default)
			)
			(layer "F.SilkS")
		)
		(fp_line
			(start 0 0.381)
			(end 0 -0.381)
			(stroke
				(width 0.1524)
				(type default)
			)
			(layer "F.SilkS")
		)
		(fp_line
			(start -0.7874 0.4064)
			(end -0.7874 -0.4064)
			(stroke
				(width 0.1524)
				(type default)
			)
			(layer "F.SilkS")
		)
		(fp_line
			(start -0.7874 -0.4064)
			(end 0.7874 -0.4064)
			(stroke
				(width 0.1524)
				(type default)
			)
			(layer "F.SilkS")
		)
		(fp_poly
			(pts
				(xy -0.5334 0.254) (xy -0.635 0.254) (xy -0.635 0.2286) (xy -0.635 -0.254) (xy -0.5334 -0.254) (xy -0.5334 -0.2794)
				(xy 0.5334 -0.2794) (xy 0.5334 -0.254) (xy 0.635 -0.254) (xy 0.635 0.254) (xy 0.5334 0.254) (xy 0.5334 0.2794)
				(xy -0.508 0.2794) (xy -0.5334 0.2794)
			)
			(stroke
				(width 0)
				(type default)
			)
			(fill no)
			(layer "F.CrtYd")
		)
		(pad "1" smd rect
			(at 0.40005 0 180)
			(size 0.4572 0.508)
			(layers "F.Cu" "F.Mask" "F.Paste")
			(net "P3V3_NODE1")
		)
		(pad "2" smd rect
			(at -0.40005 0 180)
			(size 0.4572 0.508)
			(layers "F.Cu" "F.Mask" "F.Paste")
			(net "GND")
		)
	)
	(footprint ""
		(layer "F.Cu")
		(at 80.24876 -185.205624 -90)
		(property "Reference" "R901"
			(at -4.198112 1.795272 90)
			(unlocked yes)
			(layer "F.SilkS")
			(effects
				(font
					(size 0.7874 0.5842)
					(thickness 0.1524)
				)
				(justify left)
			)
		)
		(property "Value" ""
			(at 0 0 270)
			(layer "F.Fab")
			(effects
				(font
					(size 1.27 1.27)
				)
			)
		)
		(duplicate_pad_numbers_are_jumpers no)
		(fp_line
			(start -0.7874 0.4064)
			(end -0.7874 -0.4064)
			(stroke
				(width 0.1524)
				(type default)
			)
			(layer "F.SilkS")
		)
		(fp_line
			(start 0.7874 0.4064)
			(end -0.7874 0.4064)
			(stroke
				(width 0.1524)
				(type default)
			)
			(layer "F.SilkS")
		)
		(fp_line
			(start -0.7874 -0.4064)
			(end 0.7874 -0.4064)
			(stroke
				(width 0.1524)
				(type default)
			)
			(layer "F.SilkS")
		)
		(fp_line
			(start 0.7874 -0.4064)
			(end 0.7874 0.4064)
			(stroke
				(width 0.1524)
				(type default)
			)
			(layer "F.SilkS")
		)
		(fp_poly
			(pts
				(xy -0.508 0.2794) (xy -0.508 0.2286) (xy -0.635 0.2286) (xy -0.635 -0.254) (xy -0.5334 -0.254)
				(xy -0.5334 -0.2794) (xy 0.5334 -0.2794) (xy 0.5334 -0.254) (xy 0.635 -0.254) (xy 0.635 0.254) (xy 0.5334 0.254)
				(xy 0.5334 0.2794)
			)
			(stroke
				(width 0)
				(type default)
			)
			(fill no)
			(layer "F.CrtYd")
		)
		(pad "1" smd rect
			(at 0.40005 0 270)
			(size 0.4572 0.508)
			(layers "F.Cu" "F.Mask" "F.Paste")
			(net "T4_NODE3_EN")
		)
		(pad "2" smd rect
			(at -0.40005 0 270)
			(size 0.4572 0.508)
			(layers "F.Cu" "F.Mask" "F.Paste")
			(net "T4_NODE3_EN_R")
		)
	)
)
